FILE_TYPE = CONNECTIVITY;
{Allegro Design Entry HDL 16.6-p007 (v16-6-112F) 10/10/2012}
"PAGE_NUMBER" = 89;
0"NC";
1"GND\g";
2"PVPP_ABC\g";
3"P3V3_STBY\g";
4"P3V3_STBY\g";
5"GND\g";
6"GND\g";
7"GND\g";
8"PVPP_ABC\g";
9"GND\g";
10"GND\g";
11"P3V3_STBY\g";
12"IRQ_DIMM_SAVE_N";
13"FM_ADR_COMPLETE_KLM_N";
14"FM_ADR_COMPLETE_GHJ_N";
15"FM_ADR_COMPLETE_CPU1_N";
16"FM_ADR_COMPLETE_ABC_N";
17"FM_ADR_COMPLETE_DLY";
18"FM_ADR_COMPLETE";
19"IRQ_DIMM_SAVE_R_N";
20"IRQ_DIMM_SAVE_CPU1_R_N";
21"FM_ADR_SMI_GPIO_N";
22"IRQ_DIMM_SAVE_LVT3_CPU1";
23"IRQ_DIMM_SAVE_LVT3_N";
24"IRQ_DIMM_SAVE_LVT3";
25"FM_ADR_COMPLETE_CPU1_R";
26"FM_ADR_COMPLETE_R";
27"FM_ADR_COMPLETE_DEF_N";
28"FM_ADR_COMPLETE_CPU0_R";
%"RES"
"1","(-2250,3025)","0","mstr_discrete","I1";
;
CDS_SEC"1"
TOLERANCE"5%"
VALUE"0.0"
LOCATION"R4T2"
PART_NUMBER"G21497-005"
WATTAGE"1/16W"
PACK_TYPE"0402"
MATERIAL"EMPTY"
CDS_LOCATION"R4T2"
CDS_LIB"mstr_discrete"
SEC"1"
ROOM"NV_DIMM"
SEC_TYPE"0402"
BOM_COST"MEM_NV";
"B"
$PN"2"26;
"A"
$PN"1"18;
%"GND"
"1","(-450,2525)","0","mstr_symbols","I16";
;
SIZE"1B"
CDS_LIB"mstr_symbols"
VOLTAGE"0.0V"
BODY_TYPE"PLUMBING"
HDL_POWER"GND";
"A\NAC"1;
%"PVPP_ABC"
"1","(-450,3575)","0","mstr_symbols","I17";
;
VOLTAGE"2.5V"
CDS_LIB"mstr_symbols"
BODY_TYPE"PLUMBING"
HDL_POWER"PVPP_ABC";
"G\NAC"2;
%"RES"
"1","(-2250,2725)","0","mstr_discrete","I2";
;
CDS_SEC"1"
VALUE"0.0"
TOLERANCE"5%"
LOCATION"R4T1"
PART_NUMBER"G21497-005"
PACK_TYPE"0402"
MATERIAL"CHIP"
WATTAGE"1/16W"
ROOM"NV_DIMM"
CDS_LOCATION"R4T1"
SEC"1"
CDS_LIB"mstr_discrete"
BOM_COST"MEM_NV"
SEC_TYPE"0402";
"B"
$PN"2"26;
"A"
$PN"1"17;
%"RES"
"1","(3225,3525)","0","mstr_discrete","I23";
;
VALUE"0.0"
MATERIAL"EMPTY"
LOCATION"R2P12"
TOLERANCE"5%"
PART_NUMBER"G21497-005"
WATTAGE"1/16W"
PACK_TYPE"0402"
BOM_COST"MEM_NV"
CDS_SEC"1"
$SEC"1"
ROOM"NV_DIMM"
CDS_LOCATION"R2P12"
CDS_LIB"mstr_discrete";
"B"
$PN"2"21;
"A"
$PN"1"23;
%"RES"
"2","(1750,4500)","0","mstr_discrete","I26";
;
PACK_TYPE"0402"
PART_NUMBER"G21796-072"
VALUE"4.75K"
WATTAGE"1/16W"
MATERIAL"CHIP"
TOLERANCE"1%"
LOCATION"R8D29"
CDS_LIB"mstr_discrete"
CDS_LOCATION"R8D29"
ROOM"NVDIMM"
$SEC"1"
CDS_SEC"1";
"A"
$PN"1"3;
"B"
$PN"2"24;
%"RES"
"2","(2450,4725)","0","mstr_discrete","I27";
;
PACK_TYPE"0402"
PART_NUMBER"G21796-072"
LOCATION"R8D31"
TOLERANCE"1%"
VALUE"4.75K"
MATERIAL"CHIP"
WATTAGE"1/16W"
CDS_SEC"1"
$SEC"1"
CDS_LOCATION"R8D31"
ROOM"NVDIMM"
CDS_LIB"mstr_discrete";
"A"
$PN"1"4;
"B"
$PN"2"23;
%"P3V3_STBY"
"1","(1750,4725)","0","mstr_symbols","I28";
;
VOLTAGE"3.3V"
SIZE"1B"
CDS_LIB"mstr_symbols"
BODY_TYPE"PLUMBING"
HDL_POWER"P3V3_STBY";
"G\NAC"3;
%"P3V3_STBY"
"1","(2450,4950)","0","mstr_symbols","I29";
;
SIZE"1B"
CDS_LIB"mstr_symbols"
VOLTAGE"3.3V"
BODY_TYPE"PLUMBING"
HDL_POWER"P3V3_STBY";
"G\NAC"4;
%"RES"
"1","(350,3125)","0","mstr_discrete","I3";
;
CDS_SEC"1"
WATTAGE"1/16W"
TOLERANCE"1%"
PART_NUMBER"G21796-047"
PACK_TYPE"0402"
LOCATION"R6F4"
VALUE"49.9"
MATERIAL"CHIP"
BOM_COST"MEM_NV"
SEC_TYPE"0402"
SEC"1"
ROOM"NV_DIMM"
CDS_LOCATION"R6F4"
CDS_LIB"mstr_discrete";
"B"
$PN"2"16;
"A"
$PN"1"12;
%"GND"
"1","(2450,3950)","0","mstr_symbols","I30";
;
SIZE"1B"
CDS_LIB"mstr_symbols"
VOLTAGE"0.0V"
BODY_TYPE"PLUMBING"
HDL_POWER"GND";
"A\NAC"5;
%"GND"
"1","(1750,3475)","0","mstr_symbols","I31";
;
SIZE"1B"
VOLTAGE"0.0V"
CDS_LIB"mstr_symbols"
BODY_TYPE"PLUMBING"
HDL_POWER"GND";
"A\NAC"6;
%"RES"
"1","(775,3700)","0","mstr_discrete","I34";
;
CDS_SEC"1"
MATERIAL"CHIP"
PACK_TYPE"0402"
TOLERANCE"1%"
PART_NUMBER"G21796-016"
WATTAGE"1/16W"
VALUE"10.0K"
LOCATION"R8D30"
SEC_TYPE"0402"
CDS_LIB"mstr_discrete"
BOM_COST"MEM_NV"
SEC"1"
CDS_LOCATION"R8D30"
ROOM"NV_DIMM";
"B"
$PN"2"19;
"A"
$PN"1"12;
%"NPN_DUAL"
"1","(1700,3700)","0","mstr_discrete","I35";
;
CDS_SEC"1"
VALUE"MBT3904"
MATERIAL"XSTR"
LOCATION"Q8D1"
PART_NUMBER"C52264-001"
ROOM"NV_DIMM"
SEC"1"
CDS_LIB"mstr_discrete"
SEC_TYPE"SSOPLF"
BOM_COST"MEM_NV"
PACK_TYPE"SSOPLF"
CDS_LOCATION"Q8D1";
"C <SIZE-1..0>"
$PN"3"24;
"B <SIZE-1..0>"
$PN"5"19;
"E <SIZE-1..0>"
$PN"4"6;
%"GND"
"1","(-450,1350)","0","mstr_symbols","I39";
;
SIZE"1B"
CDS_LIB"mstr_symbols"
VOLTAGE"0.0V"
BODY_TYPE"PLUMBING"
HDL_POWER"GND";
"A\NAC"7;
%"RES"
"1","(350,2825)","0","mstr_discrete","I4";
;
CDS_SEC"1"
VALUE"49.9"
PART_NUMBER"G21796-047"
PACK_TYPE"0402"
TOLERANCE"1%"
MATERIAL"CHIP"
WATTAGE"1/16W"
LOCATION"R6F1"
ROOM"NV_DIMM"
SEC"1"
SEC_TYPE"0402"
BOM_COST"MEM_NV"
CDS_LIB"mstr_discrete"
CDS_LOCATION"R6F1";
"B"
$PN"2"27;
"A"
$PN"1"12;
%"RES"
"2","(-450,2175)","0","mstr_discrete","I40";
;
CDS_SEC"1"
WATTAGE"1/16W"
TOLERANCE"1%"
MATERIAL"CHIP"
PART_NUMBER"G21796-016"
PACK_TYPE"0402"
LOCATION"R6W29"
VALUE"10.0K"
CDS_LOCATION"R6W29"
SEC"1"
SEC_TYPE"0402"
BOM_COST"MEM_NV"
ROOM"NV_DIMM"
CDS_LIB"mstr_discrete";
"A"
$PN"1"8;
"B"
$PN"2"15;
%"PVPP_ABC"
"1","(-450,2425)","0","mstr_symbols","I41";
;
VOLTAGE"2.5V"
CDS_LIB"mstr_symbols"
BODY_TYPE"PLUMBING"
HDL_POWER"PVPP_ABC";
"G\NAC"8;
%"RES"
"1","(1000,2500)","0","mstr_discrete","I45";
;
CDS_SEC"1"
VALUE"10.0K"
WATTAGE"1/16W"
TOLERANCE"1%"
PACK_TYPE"0402"
MATERIAL"CHIP"
PART_NUMBER"G21796-016"
LOCATION"WR8D30"
CDS_LOCATION"WR8D30"
SEC_TYPE"0402"
CDS_LIB"mstr_discrete"
BOM_COST"MEM_NV"
SEC"1"
ROOM"NV_DIMM";
"B"
$PN"2"20;
"A"
$PN"1"15;
%"NPN_DUAL"
"1","(2400,4175)","0","mstr_discrete","I46";
;
VALUE"MBT3904"
MATERIAL"XSTR"
PART_NUMBER"C52264-001"
LOCATION"Q8D1"
CDS_LIB"mstr_discrete"
ROOM"NV_DIMM"
SEC"2"
SEC_TYPE"SSOPLF"
BOM_COST"MEM_NV"
PACK_TYPE"SSOPLF"
CDS_SEC"2"
CDS_LOCATION"Q8D1";
"C <SIZE-1..0>"
$PN"6"23;
"B <SIZE-1..0>"
$PN"2"24;
"E <SIZE-1..0>"
$PN"1"5;
%"GND"
"1","(2200,2275)","0","mstr_symbols","I47";
;
SIZE"1B"
VOLTAGE"0.0V"
CDS_LIB"mstr_symbols"
BODY_TYPE"PLUMBING"
HDL_POWER"GND";
"A\NAC"9;
%"GND"
"1","(2950,2750)","0","mstr_symbols","I48";
;
SIZE"1B"
CDS_LIB"mstr_symbols"
VOLTAGE"0.0V"
BODY_TYPE"PLUMBING"
HDL_POWER"GND";
"A\NAC"10;
%"RES"
"2","(2200,3250)","0","mstr_discrete","I49";
;
CDS_SEC"1"
LOCATION"R8W9"
MATERIAL"CHIP"
PACK_TYPE"0402"
PART_NUMBER"G21796-072"
TOLERANCE"1%"
WATTAGE"1/16W"
VALUE"4.75K"
ROOM"NVDIMM"
CDS_LIB"mstr_discrete"
SEC_TYPE"0402"
SEC"1"
CDS_LOCATION"R8W9";
"A"
$PN"1"11;
"B"
$PN"2"22;
%"RES"
"1","(350,1950)","0","mstr_discrete","I5";
;
CDS_SEC"1"
PACK_TYPE"0402"
PART_NUMBER"G21796-047"
VALUE"49.9"
LOCATION"R6F5"
TOLERANCE"1%"
MATERIAL"CHIP"
WATTAGE"1/16W"
CDS_LIB"mstr_discrete"
CDS_LOCATION"R6F5"
ROOM"NV_DIMM"
SEC"1"
BOM_COST"MEM_NV"
SEC_TYPE"0402";
"B"
$PN"2"14;
"A"
$PN"1"15;
%"P3V3_STBY"
"1","(2200,3525)","0","mstr_symbols","I50";
;
CDS_LIB"mstr_symbols"
SIZE"1B"
VOLTAGE"3.3V"
BODY_TYPE"PLUMBING"
HDL_POWER"P3V3_STBY";
"G\NAC"11;
%"NPN_DUAL"
"1","(2900,2975)","0","mstr_discrete","I51";
;
VALUE"MBT3904"
LOCATION"Q8W1"
MATERIAL"XSTR"
PART_NUMBER"C52264-001"
CDS_LIB"mstr_discrete"
ROOM"NV_DIMM"
SEC"2"
SEC_TYPE"SSOPLF"
BOM_COST"MEM_NV"
PACK_TYPE"SSOPLF"
CDS_SEC"2"
CDS_LOCATION"Q8W1";
"C <SIZE-1..0>"
$PN"6"23;
"B <SIZE-1..0>"
$PN"2"22;
"E <SIZE-1..0>"
$PN"1"10;
%"NPN_DUAL"
"1","(2150,2500)","0","mstr_discrete","I52";
;
CDS_SEC"1"
LOCATION"Q8W1"
MATERIAL"XSTR"
VALUE"MBT3904"
PART_NUMBER"C52264-001"
ROOM"NV_DIMM"
SEC"1"
CDS_LIB"mstr_discrete"
SEC_TYPE"SSOPLF"
BOM_COST"MEM_NV"
PACK_TYPE"SSOPLF"
CDS_LOCATION"Q8W1";
"C <SIZE-1..0>"
$PN"3"22;
"B <SIZE-1..0>"
$PN"5"20;
"E <SIZE-1..0>"
$PN"4"9;
%"NPN"
"1","(-500,2725)","0","mstr_discrete","I53";
;
PART_NUMBER"C52245-001"
MATERIAL"IC"
PACK_TYPE"SM"
LOCATION"Q1F1"
VALUE"MMBT3904"
CDS_SEC"1"
BOM_COST"PROC_SIDEBAND"
SEC_TYPE"SM"
SEC"1"
ROOM"PROC_SIDEBAND"
CDS_LIB"mstr_discrete"
CDS_LOCATION"Q1F1";
"C"
$PN"3"12;
"E"
$PN"2"1;
"B"
$PN"1"28;
%"RES"
"1","(-1350,2725)","0","mstr_discrete","I54";
;
CDS_SEC"1"
WATTAGE"1/16W"
VALUE"330"
TOLERANCE"5%"
MATERIAL"CHIP"
LOCATION"R1W32"
PART_NUMBER"G21497-028"
PACK_TYPE"0402"
ROOM"UART_MUX"
BOM_COST"DEBUG"
SEC_TYPE"0402"
CDS_LIB"mstr_discrete"
SEC"1"
CDS_LOCATION"R1W32";
"B"
$PN"2"28;
"A"
$PN"1"26;
%"NPN"
"1","(-500,1550)","0","mstr_discrete","I55";
;
PACK_TYPE"SM"
VALUE"MMBT3904"
PART_NUMBER"C52245-001"
LOCATION"Q1W6"
MATERIAL"IC"
CDS_LIB"mstr_discrete"
ROOM"PROC_SIDEBAND"
SEC"1"
SEC_TYPE"SM"
BOM_COST"PROC_SIDEBAND"
CDS_SEC"1"
CDS_LOCATION"Q1W6";
"C"
$PN"3"15;
"E"
$PN"2"7;
"B"
$PN"1"25;
%"RES"
"1","(-1350,1550)","0","mstr_discrete","I56";
;
CDS_SEC"1"
WATTAGE"1/16W"
PACK_TYPE"0402"
MATERIAL"CHIP"
LOCATION"R1W31"
VALUE"330"
TOLERANCE"5%"
PART_NUMBER"G21497-028"
SEC"1"
CDS_LIB"mstr_discrete"
SEC_TYPE"0402"
BOM_COST"DEBUG"
ROOM"UART_MUX"
CDS_LOCATION"R1W31";
"B"
$PN"2"25;
"A"
$PN"1"26;
%"RES"
"1","(350,1650)","0","mstr_discrete","I6";
;
CDS_SEC"1"
VALUE"49.9"
PACK_TYPE"0402"
TOLERANCE"1%"
MATERIAL"CHIP"
WATTAGE"1/16W"
PART_NUMBER"G21796-047"
LOCATION"R6F2"
CDS_LIB"mstr_discrete"
SEC"1"
CDS_LOCATION"R6F2"
ROOM"NV_DIMM"
BOM_COST"MEM_NV"
SEC_TYPE"0402";
"B"
$PN"2"13;
"A"
$PN"1"15;
%"RES"
"2","(-450,3325)","0","mstr_discrete","I7";
;
CDS_SEC"1"
LOCATION"R6F3"
VALUE"10.0K"
TOLERANCE"1%"
WATTAGE"1/16W"
MATERIAL"CHIP"
PACK_TYPE"0402"
PART_NUMBER"G21796-016"
SEC"1"
SEC_TYPE"0402"
BOM_COST"MEM_NV"
ROOM"NV_DIMM"
CDS_LOCATION"R6F3"
CDS_LIB"mstr_discrete";
"A"
$PN"1"2;
"B"
$PN"2"12;
END.
